# S9S_MB_2U (Grand Teton) — schematic netlist excerpt (pin names and nets, part order shuffled) for the footprints in the layout excerpt that follows; sources: Cadence DE-HDL packaged netlist, KiCad conversion of 03242023_DA0F0TMBIJ0_F0T_Motherboard_J_brd_V01_OCP.brd

R2905  Q_RES  0 5% CHIP  pkg 0402LF  page 245 : A = RST_SMB_SWITCH_N ; B = RST_SMB_SWITCH_R_N
R4079  Q_RES  10K 1% CHIP  pkg 0402LF  page 212 : A = FG_SS_EN ; B = GND

(kicad_pcb
	(version 20260206)
	(generator "pcbnew")
	(generator_version "10.0")
	(general
		(thickness 1.6)
		(legacy_teardrops no)
	)
	(paper "A4")
	(title_block
		(title "03242023_DA0F0TMBIJ0_F0T_Motherboard_J_brd_V01_OCP.brd")
		(comment 1 "Grand Teton / footprints 3229-3230 of 6105")
	)
	(layers
		(0 "F.Cu" signal "TOP")
		(4 "In1.Cu" signal "GND")
		(6 "In2.Cu" signal "IN1")
		(8 "In3.Cu" signal "GND1")
		(10 "In4.Cu" signal "IN2")
		(12 "In5.Cu" signal "GND2")
		(14 "In6.Cu" signal "IN3")
		(16 "In7.Cu" signal "GND3")
		(18 "In8.Cu" signal "VCC")
		(20 "In9.Cu" signal "VCC1")
		(22 "In10.Cu" signal "GND4")
		(24 "In11.Cu" signal "IN4")
		(26 "In12.Cu" signal "GND5")
		(28 "In13.Cu" signal "IN5")
		(30 "In14.Cu" signal "GND6")
		(32 "In15.Cu" signal "IN6")
		(34 "In16.Cu" signal "GND7")
		(2 "B.Cu" signal "BOTTOM")
		(9 "F.Adhes" user "F.Adhesive")
		(11 "B.Adhes" user "B.Adhesive")
		(13 "F.Paste" user "Package Geometry/Pastemask Top")
		(15 "B.Paste" user "Package Geometry/Pastemask Bottom")
		(5 "F.SilkS" user "Ref Des/Silkscreen Top")
		(7 "B.SilkS" user "Ref Des/Silkscreen Bottom")
		(1 "F.Mask" user "Board Geometry/Soldermask Top")
		(3 "B.Mask" user "Board Geometry/Soldermask Bottom")
		(17 "Dwgs.User" user "User.Drawings")
		(19 "Cmts.User" user "User.Comments")
		(21 "Eco1.User" user "User.Eco1")
		(23 "Eco2.User" user "User.Eco2")
		(25 "Edge.Cuts" user "Board Geometry/Outline")
		(27 "Margin" user)
		(31 "F.CrtYd" user "Package Geometry/Place Bound Top")
		(29 "B.CrtYd" user "Package Geometry/Place Bound Bottom")
		(35 "F.Fab" user "Ref Des/Assembly Top")
		(33 "B.Fab" user "Ref Des/Assembly Bottom")
	)
	(footprint ""
		(layer "F.Cu")
		(at 236.599984 -245.411498 -90)
		(property "Reference" "R4079"
			(at 0 0 270)
			(layer "F.SilkS")
			(hide yes)
			(effects
				(font
					(size 1.27 1.27)
				)
			)
		)
		(property "Value" ""
			(at 0 0 270)
			(layer "F.Fab")
			(effects
				(font
					(size 1.27 1.27)
				)
			)
		)
		(duplicate_pad_numbers_are_jumpers no)
		(fp_line
			(start -0.7874 0.4064)
			(end -0.7874 -0.4064)
			(stroke
				(width 0.1524)
				(type default)
			)
			(layer "F.SilkS")
		)
		(fp_line
			(start 0.7874 0.4064)
			(end -0.7874 0.4064)
			(stroke
				(width 0.1524)
				(type default)
			)
			(layer "F.SilkS")
		)
		(fp_line
			(start -0.7874 -0.4064)
			(end 0.7874 -0.4064)
			(stroke
				(width 0.1524)
				(type default)
			)
			(layer "F.SilkS")
		)
		(fp_line
			(start 0.7874 -0.4064)
			(end 0.7874 0.4064)
			(stroke
				(width 0.1524)
				(type default)
			)
			(layer "F.SilkS")
		)
		(fp_line
			(start -0.67945 0.3048)
			(end -0.67945 -0.305054)
			(stroke
				(width 0.1)
				(type default)
			)
			(layer "F.Fab")
		)
		(fp_line
			(start -0.12065 0.3048)
			(end -0.67945 0.3048)
			(stroke
				(width 0.1)
				(type default)
			)
			(layer "F.Fab")
		)
		(fp_line
			(start 0.120396 0.3048)
			(end 0.120396 0.2794)
			(stroke
				(width 0.1)
				(type default)
			)
			(layer "F.Fab")
		)
		(fp_line
			(start 0.67945 0.3048)
			(end 0.120396 0.3048)
			(stroke
				(width 0.1)
				(type default)
			)
			(layer "F.Fab")
		)
		(fp_line
			(start -0.12065 0.2794)
			(end -0.12065 0.3048)
			(stroke
				(width 0.1)
				(type default)
			)
			(layer "F.Fab")
		)
		(fp_line
			(start 0.120396 0.2794)
			(end -0.12065 0.2794)
			(stroke
				(width 0.1)
				(type default)
			)
			(layer "F.Fab")
		)
		(fp_line
			(start -0.12065 -0.2794)
			(end 0.12065 -0.2794)
			(stroke
				(width 0.1)
				(type default)
			)
			(layer "F.Fab")
		)
		(fp_line
			(start 0.12065 -0.2794)
			(end 0.12065 -0.3048)
			(stroke
				(width 0.1)
				(type default)
			)
			(layer "F.Fab")
		)
		(fp_line
			(start 0.12065 -0.3048)
			(end 0.67945 -0.3048)
			(stroke
				(width 0.1)
				(type default)
			)
			(layer "F.Fab")
		)
		(fp_line
			(start 0.67945 -0.3048)
			(end 0.67945 0.3048)
			(stroke
				(width 0.1)
				(type default)
			)
			(layer "F.Fab")
		)
		(fp_line
			(start -0.67945 -0.305054)
			(end -0.12065 -0.305054)
			(stroke
				(width 0.1)
				(type default)
			)
			(layer "F.Fab")
		)
		(fp_line
			(start -0.12065 -0.305054)
			(end -0.12065 -0.2794)
			(stroke
				(width 0.1)
				(type default)
			)
			(layer "F.Fab")
		)
		(pad "1" smd circle
			(at -0.40005 0 270)
			(size 0 0)
			(layers "F.Cu" "F.Mask" "F.Paste")
			(net "FG_SS_EN")
		)
		(pad "2" smd circle
			(at 0.40005 0 270)
			(size 0 0)
			(layers "F.Cu" "F.Mask" "F.Paste")
			(net "GND")
		)
	)
	(footprint ""
		(layer "F.Cu")
		(at 166.17823 -73.754234)
		(property "Reference" "R2905"
			(at 0 0 0)
			(layer "F.SilkS")
			(hide yes)
			(effects
				(font
					(size 1.27 1.27)
				)
			)
		)
		(property "Value" ""
			(at 0 0 0)
			(layer "F.Fab")
			(effects
				(font
					(size 1.27 1.27)
				)
			)
		)
		(duplicate_pad_numbers_are_jumpers no)
		(fp_line
			(start -0.7874 -0.4064)
			(end 0.7874 -0.4064)
			(stroke
				(width 0.1524)
				(type default)
			)
			(layer "F.SilkS")
		)
		(fp_line
			(start -0.7874 0.4064)
			(end -0.7874 -0.4064)
			(stroke
				(width 0.1524)
				(type default)
			)
			(layer "F.SilkS")
		)
		(fp_line
			(start 0.7874 -0.4064)
			(end 0.7874 0.4064)
			(stroke
				(width 0.1524)
				(type default)
			)
			(layer "F.SilkS")
		)
		(fp_line
			(start 0.7874 0.4064)
			(end -0.7874 0.4064)
			(stroke
				(width 0.1524)
				(type default)
			)
			(layer "F.SilkS")
		)
		(fp_line
			(start -0.67945 -0.305054)
			(end -0.12065 -0.305054)
			(stroke
				(width 0.1)
				(type default)
			)
			(layer "F.Fab")
		)
		(fp_line
			(start -0.67945 0.3048)
			(end -0.67945 -0.305054)
			(stroke
				(width 0.1)
				(type default)
			)
			(layer "F.Fab")
		)
		(fp_line
			(start -0.12065 -0.305054)
			(end -0.12065 -0.2794)
			(stroke
				(width 0.1)
				(type default)
			)
			(layer "F.Fab")
		)
		(fp_line
			(start -0.12065 -0.2794)
			(end 0.12065 -0.2794)
			(stroke
				(width 0.1)
				(type default)
			)
			(layer "F.Fab")
		)
		(fp_line
			(start -0.12065 0.2794)
			(end -0.12065 0.3048)
			(stroke
				(width 0.1)
				(type default)
			)
			(layer "F.Fab")
		)
		(fp_line
			(start -0.12065 0.3048)
			(end -0.67945 0.3048)
			(stroke
				(width 0.1)
				(type default)
			)
			(layer "F.Fab")
		)
		(fp_line
			(start 0.120396 0.2794)
			(end -0.12065 0.2794)
			(stroke
				(width 0.1)
				(type default)
			)
			(layer "F.Fab")
		)
		(fp_line
			(start 0.120396 0.3048)
			(end 0.120396 0.2794)
			(stroke
				(width 0.1)
				(type default)
			)
			(layer "F.Fab")
		)
		(fp_line
			(start 0.12065 -0.3048)
			(end 0.67945 -0.3048)
			(stroke
				(width 0.1)
				(type default)
			)
			(layer "F.Fab")
		)
		(fp_line
			(start 0.12065 -0.2794)
			(end 0.12065 -0.3048)
			(stroke
				(width 0.1)
				(type default)
			)
			(layer "F.Fab")
		)
		(fp_line
			(start 0.67945 -0.3048)
			(end 0.67945 0.3048)
			(stroke
				(width 0.1)
				(type default)
			)
			(layer "F.Fab")
		)
		(fp_line
			(start 0.67945 0.3048)
			(end 0.120396 0.3048)
			(stroke
				(width 0.1)
				(type default)
			)
			(layer "F.Fab")
		)
		(pad "1" smd circle
			(at -0.40005 0)
			(size 0 0)
			(layers "F.Cu" "F.Mask" "F.Paste")
			(net "RST_SMB_SWITCH_N")
		)
		(pad "2" smd circle
			(at 0.40005 0)
			(size 0 0)
			(layers "F.Cu" "F.Mask" "F.Paste")
			(net "RST_SMB_SWITCH_R_N")
		)
	)
)
